(kicad_pcb
	(version 20241229)
	(generator "pcbnew")
	(generator_version "9.0")
	(general
		(thickness 1.711)
		(legacy_teardrops no)
	)
	(paper "A4")
	(title_block
		(title "Antmicro Baseboard for Jetson AGX Thor")
		(date "2026-02-18")
		(rev "1.1.0")
		(company "Antmicro Ltd")
		(comment 1 "www.antmicro.com")
		(comment 9 "footprints 325-329 of 1170")
	)
	(layers
		(0 "F.Cu" signal)
		(4 "In1.Cu" signal)
		(6 "In2.Cu" signal)
		(8 "In3.Cu" signal)
		(10 "In4.Cu" jumper)
		(12 "In5.Cu" signal)
		(14 "In6.Cu" signal)
		(16 "In7.Cu" signal)
		(18 "In8.Cu" signal)
		(2 "B.Cu" signal)
		(9 "F.Adhes" user "F.Adhesive")
		(11 "B.Adhes" user "B.Adhesive")
		(13 "F.Paste" user)
		(15 "B.Paste" user)
		(5 "F.SilkS" user "F.Silkscreen")
		(7 "B.SilkS" user "B.Silkscreen")
		(1 "F.Mask" user)
		(3 "B.Mask" user)
		(17 "Dwgs.User" user "User.Drawings")
		(19 "Cmts.User" user "User.Comments")
		(21 "Eco1.User" user "User.Eco1")
		(23 "Eco2.User" user "User.Eco2")
		(25 "Edge.Cuts" user)
		(27 "Margin" user)
		(31 "F.CrtYd" user "F.Courtyard")
		(29 "B.CrtYd" user "B.Courtyard")
		(35 "F.Fab" user)
		(33 "B.Fab" user)
	)
	(footprint "antmicro-footprints:R_0402_1005Metric"
		(layer "F.Cu")
		(at 179.604468 86.725 -90)
		(descr "Resistor SMD 0402")
		(tags "resistor SMD 0402")
		(property "Reference" "R20"
			(at -2.96 0.32 90)
			(layer "F.SilkS")
			(effects
				(font
					(size 0.7 0.7)
					(thickness 0.15)
				)
				(justify right top)
			)
		)
		(property "Value" "R_100k_0402"
			(at -1.011843 1.772047 90)
			(layer "F.Fab")
			(effects
				(font
					(size 0.7 0.7)
					(thickness 0.15)
				)
				(justify right top)
			)
		)
		(property "Datasheet" "https://www.bourns.com/docs/product-datasheets/cr.pdf"
			(at 0 0 90)
			(layer "F.Fab")
			(hide yes)
			(effects
				(font
					(size 1.27 1.27)
					(thickness 0.15)
				)
			)
		)
		(property "Description" "SMD Chip Resistor, 100 kohm, ± 1%, 62.5 mW, 0402 [1005 Metric], Thick Film, General Purpose"
			(at 0 0 90)
			(layer "F.Fab")
			(hide yes)
			(effects
				(font
					(size 1.27 1.27)
					(thickness 0.15)
				)
			)
		)
		(property "MPN" "CR0402-FX-1003GLF"
			(at 0 0 270)
			(unlocked yes)
			(layer "F.Fab")
			(hide yes)
			(effects
				(font
					(size 1 1)
					(thickness 0.15)
				)
			)
		)
		(property "Manufacturer" "Bourns"
			(at 0 0 270)
			(unlocked yes)
			(layer "F.Fab")
			(hide yes)
			(effects
				(font
					(size 1 1)
					(thickness 0.15)
				)
			)
		)
		(property "License" "Apache-2.0"
			(at 0 0 270)
			(unlocked yes)
			(layer "F.Fab")
			(hide yes)
			(effects
				(font
					(size 1 1)
					(thickness 0.15)
				)
			)
		)
		(property "Author" "Antmicro"
			(at 0 0 270)
			(unlocked yes)
			(layer "F.Fab")
			(hide yes)
			(effects
				(font
					(size 1 1)
					(thickness 0.15)
				)
			)
		)
		(property "Val" "100k"
			(at 0 0 270)
			(unlocked yes)
			(layer "F.Fab")
			(hide yes)
			(effects
				(font
					(size 1 1)
					(thickness 0.15)
				)
			)
		)
		(property "Tolerance" "1%"
			(at 0 0 270)
			(unlocked yes)
			(layer "F.Fab")
			(hide yes)
			(effects
				(font
					(size 1 1)
					(thickness 0.15)
				)
			)
		)
		(component_classes
			(class "DCDC_SOM")
		)
		(sheetname "/DCDC/")
		(sheetfile "dcdc.kicad_sch")
		(attr smd)
		(fp_rect
			(start -0.925 -0.47)
			(end 0.925 0.47)
			(stroke
				(width 0.05)
				(type default)
			)
			(fill no)
			(layer "F.CrtYd")
		)
		(fp_rect
			(start -0.5 -0.25)
			(end 0.5 0.25)
			(stroke
				(width 0.15)
				(type solid)
			)
			(fill no)
			(layer "F.Fab")
		)
		(fp_text user "Author: Antmicro"
			(at -0.95 4.169 90)
			(layer "F.Fab")
			(effects
				(font
					(size 0.7 0.7)
					(thickness 0.15)
				)
				(justify right top)
			)
		)
		(fp_text user "License: Apache-2.0"
			(at -0.95 5.169 90)
			(layer "F.Fab")
			(effects
				(font
					(size 0.7 0.7)
					(thickness 0.15)
				)
				(justify right top)
			)
		)
		(fp_text user "${REFERENCE}"
			(at -0.95 3.168 90)
			(layer "F.Fab")
			(effects
				(font
					(size 0.7 0.7)
					(thickness 0.15)
				)
				(justify right top)
			)
		)
		(pad "1" smd roundrect
			(at -0.48 0 270)
			(size 0.59 0.64)
			(layers "F.Cu" "F.Mask" "F.Paste")
			(roundrect_rratio 0.25)
			(net 1 "GND")
			(pintype "passive")
		)
		(pad "2" smd roundrect
			(at 0.48 0 270)
			(size 0.59 0.64)
			(layers "F.Cu" "F.Mask" "F.Paste")
			(roundrect_rratio 0.25)
			(net 1207 "/DCDC/16V_MODE1")
			(pintype "passive")
		)
	)
	(footprint "antmicro-footprints:TP_SMD_0.75mm"
		(layer "F.Cu")
		(at 161.72 57.14)
		(property "Reference" "TP64"
			(at -0.65 2.16 90)
			(layer "F.SilkS")
			(hide yes)
			(effects
				(font
					(size 0.7 0.7)
					(thickness 0.15)
				)
				(justify left bottom)
			)
		)
		(property "Value" "TP_0.75mm_SMD"
			(at 0 1.2 0)
			(layer "F.Fab")
			(effects
				(font
					(size 0.7 0.7)
					(thickness 0.15)
				)
				(justify left bottom)
			)
		)
		(property "Description" "SMT test point"
			(at 0 0 0)
			(layer "F.Fab")
			(hide yes)
			(effects
				(font
					(size 1.27 1.27)
					(thickness 0.15)
				)
			)
		)
		(property "MPN" ""
			(at 0 0 0)
			(unlocked yes)
			(layer "F.Fab")
			(hide yes)
			(effects
				(font
					(size 1 1)
					(thickness 0.15)
				)
			)
		)
		(property "Manufacturer" ""
			(at 0 0 0)
			(unlocked yes)
			(layer "F.Fab")
			(hide yes)
			(effects
				(font
					(size 1 1)
					(thickness 0.15)
				)
			)
		)
		(property "Author" "Antmicro"
			(at 0 0 0)
			(unlocked yes)
			(layer "F.Fab")
			(hide yes)
			(effects
				(font
					(size 1 1)
					(thickness 0.15)
				)
			)
		)
		(property "License" "Apache-2.0"
			(at 0 0 0)
			(unlocked yes)
			(layer "F.Fab")
			(hide yes)
			(effects
				(font
					(size 1 1)
					(thickness 0.15)
				)
			)
		)
		(sheetname "/Power/")
		(sheetfile "power.kicad_sch")
		(attr exclude_from_pos_files exclude_from_bom)
		(fp_circle
			(center 0 0)
			(end 0.475 0)
			(stroke
				(width 0.05)
				(type default)
			)
			(fill no)
			(layer "F.CrtYd")
		)
		(fp_text user "${REFERENCE}"
			(at -0.4 2.7 0)
			(layer "F.Fab")
			(effects
				(font
					(size 0.7 0.7)
					(thickness 0.15)
				)
				(justify left bottom)
			)
		)
		(fp_text user "License: Apache-2.0"
			(at -0.4 5.101 0)
			(layer "F.Fab")
			(effects
				(font
					(size 0.7 0.7)
					(thickness 0.15)
				)
				(justify left bottom)
			)
		)
		(fp_text user "Author: Antmicro"
			(at -0.4 3.901 0)
			(layer "F.Fab")
			(effects
				(font
					(size 0.7 0.7)
					(thickness 0.15)
				)
				(justify left bottom)
			)
		)
		(pad "1" smd circle
			(at 0 0)
			(size 0.75 0.75)
			(layers "F.Cu" "F.Mask")
			(net 282 "+1V15")
			(pinfunction "1")
			(pintype "passive")
		)
	)
	(footprint "antmicro-footprints:R_0402_1005Metric"
		(layer "F.Cu")
		(at 213.8 107 -90)
		(descr "Resistor SMD 0402")
		(tags "resistor SMD 0402")
		(property "Reference" "R255"
			(at -1.2 1.4 90)
			(layer "F.SilkS")
			(effects
				(font
					(size 0.7 0.7)
					(thickness 0.15)
				)
				(justify right top)
			)
		)
		(property "Value" "R_200k_0402"
			(at -1.011843 1.772046 90)
			(layer "F.Fab")
			(effects
				(font
					(size 0.7 0.7)
					(thickness 0.15)
				)
				(justify right top)
			)
		)
		(property "Datasheet" "https://www.bourns.com/docs/product-datasheets/cr.pdf"
			(at 0 0 90)
			(layer "F.Fab")
			(hide yes)
			(effects
				(font
					(size 1.27 1.27)
					(thickness 0.15)
				)
			)
		)
		(property "Description" "SMD Chip Resistor, 200 kohm, ± 1%, 62.5 mW, 0402 [1005 Metric], Thick Film, General Purpose"
			(at 0 0 90)
			(layer "F.Fab")
			(hide yes)
			(effects
				(font
					(size 1.27 1.27)
					(thickness 0.15)
				)
			)
		)
		(property "Manufacturer" "Bourns"
			(at 0 0 270)
			(unlocked yes)
			(layer "F.Fab")
			(hide yes)
			(effects
				(font
					(size 1 1)
					(thickness 0.15)
				)
			)
		)
		(property "MPN" "CR0402-FX-2003GLF"
			(at 0 0 270)
			(unlocked yes)
			(layer "F.Fab")
			(hide yes)
			(effects
				(font
					(size 1 1)
					(thickness 0.15)
				)
			)
		)
		(property "Val" "200k"
			(at 0 0 270)
			(unlocked yes)
			(layer "F.Fab")
			(hide yes)
			(effects
				(font
					(size 1 1)
					(thickness 0.15)
				)
			)
		)
		(property "License" "Apache-2.0"
			(at 0 0 270)
			(unlocked yes)
			(layer "F.Fab")
			(hide yes)
			(effects
				(font
					(size 1 1)
					(thickness 0.15)
				)
			)
		)
		(property "Author" "Antmicro"
			(at 0 0 270)
			(unlocked yes)
			(layer "F.Fab")
			(hide yes)
			(effects
				(font
					(size 1 1)
					(thickness 0.15)
				)
			)
		)
		(property "Tolerance" "1%"
			(at 0 0 270)
			(unlocked yes)
			(layer "F.Fab")
			(hide yes)
			(effects
				(font
					(size 1 1)
					(thickness 0.15)
				)
			)
		)
		(sheetname "/Recovery USB/")
		(sheetfile "recovery_usb.kicad_sch")
		(attr smd)
		(fp_poly
			(pts
				(xy -0.925 -0.47) (xy -0.925 0.47) (xy 0.925 0.47) (xy 0.925 -0.47)
			)
			(stroke
				(width 0.05)
				(type default)
			)
			(fill no)
			(layer "F.CrtYd")
		)
		(fp_poly
			(pts
				(xy -0.5 -0.25) (xy -0.5 0.25) (xy 0.5 0.25) (xy 0.5 -0.25)
			)
			(stroke
				(width 0.15)
				(type solid)
			)
			(fill no)
			(layer "F.Fab")
		)
		(fp_text user "${REFERENCE}"
			(at -0.95 3.168 90)
			(layer "F.Fab")
			(effects
				(font
					(size 0.7 0.7)
					(thickness 0.15)
				)
				(justify right top)
			)
		)
		(fp_text user "License: Apache-2.0"
			(at -0.949999 5.169 90)
			(layer "F.Fab")
			(effects
				(font
					(size 0.7 0.7)
					(thickness 0.15)
				)
				(justify right top)
			)
		)
		(fp_text user "Author: Antmicro"
			(at -0.95 4.169 90)
			(layer "F.Fab")
			(effects
				(font
					(size 0.7 0.7)
					(thickness 0.15)
				)
				(justify right top)
			)
		)
		(pad "1" smd roundrect
			(at -0.48 0 270)
			(size 0.59 0.64)
			(layers "F.Cu" "F.Mask" "F.Paste")
			(roundrect_rratio 0.25)
			(net 1013 "/Recovery USB/USBC2_DIR")
			(pintype "passive")
		)
		(pad "2" smd roundrect
			(at 0.48 0 270)
			(size 0.59 0.64)
			(layers "F.Cu" "F.Mask" "F.Paste")
			(roundrect_rratio 0.25)
			(net 2 "+3V3")
			(pintype "passive")
		)
	)
	(footprint "antmicro-footprints:USON-10_2.5x1mm_P0.5mm"
		(layer "F.Cu")
		(at 160.22 144.23 180)
		(descr "USON-10 2.5x1mm_ Pitch 0.5mm")
		(tags "USON-10 2.5x1mm Pitch 0.5mm")
		(property "Reference" "U16"
			(at -0.88 2.43 0)
			(layer "F.SilkS")
			(effects
				(font
					(size 0.7 0.7)
					(thickness 0.15)
				)
				(justify right top)
			)
		)
		(property "Value" "TPD4E05U06QDQARQ1"
			(at 0.018 2.499 0)
			(layer "F.Fab")
			(effects
				(font
					(size 0.7 0.7)
					(thickness 0.15)
				)
				(justify right top)
			)
		)
		(property "Datasheet" "https://www.ti.com/lit/ds/symlink/tpd4e05u06-q1.pdf?HQS=dis-mous-null-mousermode-dsf-pf-null-wwe&ts=1663591265741&ref_url=https%253A%252F%252Fwww.mouser.com%252F"
			(at 0 0 0)
			(layer "F.Fab")
			(hide yes)
			(effects
				(font
					(size 1.27 1.27)
					(thickness 0.15)
				)
			)
		)
		(property "Description" "TVS diode array, 12 kV, USON-10, 5.5 V, 0.5 pF"
			(at 0 0 0)
			(layer "F.Fab")
			(hide yes)
			(effects
				(font
					(size 1.27 1.27)
					(thickness 0.15)
				)
			)
		)
		(property "Manufacturer" "Texas Instruments"
			(at 0 0 0)
			(unlocked yes)
			(layer "F.Fab")
			(hide yes)
			(effects
				(font
					(size 1 1)
					(thickness 0.15)
				)
			)
		)
		(property "MPN" "TPD4E05U06QDQARQ1"
			(at 0 0 0)
			(unlocked yes)
			(layer "F.Fab")
			(hide yes)
			(effects
				(font
					(size 1 1)
					(thickness 0.15)
				)
			)
		)
		(property "Author" "Antmicro"
			(at 0 0 0)
			(unlocked yes)
			(layer "F.Fab")
			(hide yes)
			(effects
				(font
					(size 1 1)
					(thickness 0.15)
				)
			)
		)
		(property "License" "Apache-2.0"
			(at 0 0 0)
			(unlocked yes)
			(layer "F.Fab")
			(hide yes)
			(effects
				(font
					(size 1 1)
					(thickness 0.15)
				)
			)
		)
		(sheetname "/Peripherals/")
		(sheetfile "peripherals.kicad_sch")
		(attr smd)
		(fp_line
			(start 0.498 1.398)
			(end -0.5 1.398)
			(stroke
				(width 0.15)
				(type solid)
			)
			(layer "F.SilkS")
		)
		(fp_line
			(start 0.498 -1.401)
			(end -0.5 -1.401)
			(stroke
				(width 0.15)
				(type solid)
			)
			(layer "F.SilkS")
		)
		(fp_circle
			(center -0.68 -1.27)
			(end -0.63 -1.27)
			(stroke
				(width 0.15)
				(type solid)
			)
			(fill yes)
			(layer "F.SilkS")
		)
		(fp_rect
			(start -0.8 -1.5)
			(end 0.8 1.499)
			(stroke
				(width 0.05)
				(type solid)
			)
			(fill no)
			(layer "F.CrtYd")
		)
		(fp_line
			(start 0.498 -1.25)
			(end 0.498 1.249)
			(stroke
				(width 0.15)
				(type solid)
			)
			(layer "F.Fab")
		)
		(fp_line
			(start 0.498 -1.25)
			(end -0.25 -1.25)
			(stroke
				(width 0.15)
				(type solid)
			)
			(layer "F.Fab")
		)
		(fp_line
			(start -0.25 -1.25)
			(end -0.5 -1)
			(stroke
				(width 0.15)
				(type solid)
			)
			(layer "F.Fab")
		)
		(fp_line
			(start -0.5 1.249)
			(end 0.498 1.249)
			(stroke
				(width 0.15)
				(type solid)
			)
			(layer "F.Fab")
		)
		(fp_line
			(start -0.5 -1)
			(end -0.5 1.249)
			(stroke
				(width 0.15)
				(type solid)
			)
			(layer "F.Fab")
		)
		(fp_text user "Author: Antmicro"
			(at -0.802 5.7 0)
			(layer "F.Fab")
			(effects
				(font
					(size 0.7 0.7)
					(thickness 0.15)
				)
				(justify right top)
			)
		)
		(fp_text user "License: Apache-2.0"
			(at -0.802 6.9 0)
			(layer "F.Fab")
			(effects
				(font
					(size 0.7 0.7)
					(thickness 0.15)
				)
				(justify right top)
			)
		)
		(fp_text user "${REFERENCE}"
			(at -0.802 4.498 0)
			(layer "F.Fab")
			(effects
				(font
					(size 0.7 0.7)
					(thickness 0.15)
				)
				(justify right top)
			)
		)
		(pad "1" smd roundrect
			(at -0.387 -1 90)
			(size 0.25 0.55)
			(layers "F.Cu" "F.Mask" "F.Paste")
			(roundrect_rratio 0.25)
			(net 1 "GND")
			(pintype "passive")
		)
		(pad "2" smd roundrect
			(at -0.387 -0.5 90)
			(size 0.25 0.55)
			(layers "F.Cu" "F.Mask" "F.Paste")
			(roundrect_rratio 0.25)
			(net 279 "/Peripherals/FAN_TACH_5V")
			(pintype "passive")
		)
		(pad "3" smd roundrect
			(at -0.387 0 90)
			(size 0.4 0.55)
			(layers "F.Cu" "F.Mask" "F.Paste")
			(roundrect_rratio 0.25)
			(net 1 "GND")
			(pintype "power_in")
		)
		(pad "4" smd roundrect
			(at -0.387 0.498 90)
			(size 0.25 0.55)
			(layers "F.Cu" "F.Mask" "F.Paste")
			(roundrect_rratio 0.25)
			(net 281 "/Peripherals/FAN_PWM_5V")
			(pintype "passive")
		)
		(pad "5" smd roundrect
			(at -0.387 0.998 90)
			(size 0.25 0.55)
			(layers "F.Cu" "F.Mask" "F.Paste")
			(roundrect_rratio 0.25)
			(net 1 "GND")
			(pintype "passive")
		)
		(pad "6" smd roundrect
			(at 0.385 0.998 90)
			(size 0.25 0.55)
			(layers "F.Cu" "F.Mask" "F.Paste")
			(roundrect_rratio 0.25)
			(net 1 "GND")
			(pintype "passive")
		)
		(pad "7" smd roundrect
			(at 0.385 0.498 90)
			(size 0.25 0.55)
			(layers "F.Cu" "F.Mask" "F.Paste")
			(roundrect_rratio 0.25)
			(net 281 "/Peripherals/FAN_PWM_5V")
			(pintype "passive")
		)
		(pad "8" smd roundrect
			(at 0.385 0 90)
			(size 0.4 0.55)
			(layers "F.Cu" "F.Mask" "F.Paste")
			(roundrect_rratio 0.25)
			(net 1 "GND")
			(pintype "passive")
		)
		(pad "9" smd roundrect
			(at 0.385 -0.5 90)
			(size 0.25 0.55)
			(layers "F.Cu" "F.Mask" "F.Paste")
			(roundrect_rratio 0.25)
			(net 279 "/Peripherals/FAN_TACH_5V")
			(pintype "passive")
		)
		(pad "10" smd roundrect
			(at 0.385 -1 90)
			(size 0.25 0.55)
			(layers "F.Cu" "F.Mask" "F.Paste")
			(roundrect_rratio 0.25)
			(net 1 "GND")
			(pintype "passive")
		)
	)
	(footprint "antmicro-footprints:R_0402_1005Metric"
		(layer "F.Cu")
		(at 90.03 149.18)
		(descr "Resistor SMD 0402")
		(tags "resistor SMD 0402")
		(property "Reference" "R8"
			(at -1.81 2.925001 0)
			(layer "F.SilkS")
			(effects
				(font
					(size 0.7 0.7)
					(thickness 0.15)
				)
				(justify left bottom)
			)
		)
		(property "Value" "R_33R_0402"
			(at -1.011843 1.772046 0)
			(layer "F.Fab")
			(effects
				(font
					(size 0.7 0.7)
					(thickness 0.15)
				)
				(justify left bottom)
			)
		)
		(property "Datasheet" "https://www.bourns.com/docs/product-datasheets/cr.pdf"
			(at 0 0 0)
			(layer "F.Fab")
			(hide yes)
			(effects
				(font
					(size 1.27 1.27)
					(thickness 0.15)
				)
			)
		)
		(property "Description" "SMD Chip Resistor, 33 ohm, ± 1%, 62.5 mW, 0402 [1005 Metric], Thick Film, General Purpose"
			(at 0 0 0)
			(layer "F.Fab")
			(hide yes)
			(effects
				(font
					(size 1.27 1.27)
					(thickness 0.15)
				)
			)
		)
		(property "MPN" "CR0402-FX-33R0GLF"
			(at 0 0 0)
			(unlocked yes)
			(layer "F.Fab")
			(hide yes)
			(effects
				(font
					(size 1 1)
					(thickness 0.15)
				)
			)
		)
		(property "Manufacturer" "Bourns"
			(at 0 0 0)
			(unlocked yes)
			(layer "F.Fab")
			(hide yes)
			(effects
				(font
					(size 1 1)
					(thickness 0.15)
				)
			)
		)
		(property "License" "Apache-2.0"
			(at 0 0 0)
			(unlocked yes)
			(layer "F.Fab")
			(hide yes)
			(effects
				(font
					(size 1 1)
					(thickness 0.15)
				)
			)
		)
		(property "Author" "Antmicro"
			(at 0 0 0)
			(unlocked yes)
			(layer "F.Fab")
			(hide yes)
			(effects
				(font
					(size 1 1)
					(thickness 0.15)
				)
			)
		)
		(property "Val" "33R"
			(at 0 0 0)
			(unlocked yes)
			(layer "F.Fab")
			(hide yes)
			(effects
				(font
					(size 1 1)
					(thickness 0.15)
				)
			)
		)
		(property "Tolerance" "1%"
			(at 0 0 0)
			(unlocked yes)
			(layer "F.Fab")
			(hide yes)
			(effects
				(font
					(size 1 1)
					(thickness 0.15)
				)
			)
		)
		(sheetname "/SoM_IO2/")
		(sheetfile "som_io2.kicad_sch")
		(attr smd)
		(fp_poly
			(pts
				(xy -0.925 -0.47) (xy -0.925 0.47) (xy 0.925 0.47) (xy 0.925 -0.47)
			)
			(stroke
				(width 0.05)
				(type default)
			)
			(fill no)
			(layer "F.CrtYd")
		)
		(fp_poly
			(pts
				(xy -0.5 -0.25) (xy -0.5 0.25) (xy 0.5 0.25) (xy 0.5 -0.25)
			)
			(stroke
				(width 0.15)
				(type solid)
			)
			(fill no)
			(layer "F.Fab")
		)
		(fp_text user "Author: Antmicro"
			(at -0.95 4.169 0)
			(layer "F.Fab")
			(effects
				(font
					(size 0.7 0.7)
					(thickness 0.15)
				)
				(justify left bottom)
			)
		)
		(fp_text user "License: Apache-2.0"
			(at -0.949999 5.169 0)
			(layer "F.Fab")
			(effects
				(font
					(size 0.7 0.7)
					(thickness 0.15)
				)
				(justify left bottom)
			)
		)
		(fp_text user "${REFERENCE}"
			(at -0.95 3.168 0)
			(layer "F.Fab")
			(effects
				(font
					(size 0.7 0.7)
					(thickness 0.15)
				)
				(justify left bottom)
			)
		)
		(pad "1" smd roundrect
			(at -0.48 0)
			(size 0.59 0.64)
			(layers "F.Cu" "F.Mask" "F.Paste")
			(roundrect_rratio 0.25)
			(net 897 "/SoM_IO2/C2_CLK+")
			(pintype "passive")
		)
		(pad "2" smd roundrect
			(at 0.48 0)
			(size 0.59 0.64)
			(layers "F.Cu" "F.Mask" "F.Paste")
			(roundrect_rratio 0.25)
			(net 898 "/SoM_IO2/C2_REFCLK+")
			(pintype "passive")
		)
	)
)
